(kicad_pcb
	(version 20260206)
	(generator "pcbnew")
	(generator_version "10.0")
	(general
		(thickness 1.6)
		(legacy_teardrops no)
	)
	(paper "A4")
	(title_block
		(title "04192023_DAF0TMB3IC0_F0TG_MB_C_brd_V02_OCP.brd")
		(comment 1 "Grand Teton / footprints 3853-3858 of 8354")
	)
	(layers
		(0 "F.Cu" signal "TOP")
		(4 "In1.Cu" signal "GND")
		(6 "In2.Cu" signal "IN1")
		(8 "In3.Cu" signal "GND1")
		(10 "In4.Cu" signal "IN2")
		(12 "In5.Cu" signal "GND2")
		(14 "In6.Cu" signal "IN3")
		(16 "In7.Cu" signal "GND3")
		(18 "In8.Cu" signal "VCC")
		(20 "In9.Cu" signal "VCC1")
		(22 "In10.Cu" signal "GND4")
		(24 "In11.Cu" signal "IN4")
		(26 "In12.Cu" signal "GND5")
		(28 "In13.Cu" signal "IN5")
		(30 "In14.Cu" signal "GND6")
		(32 "In15.Cu" signal "IN6")
		(34 "In16.Cu" signal "GND7")
		(2 "B.Cu" signal "BOTTOM")
		(9 "F.Adhes" user "F.Adhesive")
		(11 "B.Adhes" user "B.Adhesive")
		(13 "F.Paste" user "Package Geometry/Pastemask Top")
		(15 "B.Paste" user "Package Geometry/Pastemask Bottom")
		(5 "F.SilkS" user "Ref Des/Silkscreen Top")
		(7 "B.SilkS" user "Ref Des/Silkscreen Bottom")
		(1 "F.Mask" user "Board Geometry/Soldermask Top")
		(3 "B.Mask" user "Board Geometry/Soldermask Bottom")
		(17 "Dwgs.User" user "User.Drawings")
		(19 "Cmts.User" user "User.Comments")
		(21 "Eco1.User" user "User.Eco1")
		(23 "Eco2.User" user "User.Eco2")
		(25 "Edge.Cuts" user "Board Geometry/Outline")
		(27 "Margin" user)
		(31 "F.CrtYd" user "Package Geometry/Place Bound Top")
		(29 "B.CrtYd" user "Package Geometry/Place Bound Bottom")
		(35 "F.Fab" user "Ref Des/Assembly Top")
		(33 "B.Fab" user "Ref Des/Assembly Bottom")
	)
	(footprint ""
		(layer "F.Cu")
		(at 248.59615 -268.092936 180)
		(property "Reference" "PC6500"
			(at 0 0 180)
			(layer "F.SilkS")
			(hide yes)
			(effects
				(font
					(size 1.27 1.27)
				)
			)
		)
		(property "Value" ""
			(at 0 0 180)
			(layer "F.Fab")
			(effects
				(font
					(size 1.27 1.27)
				)
			)
		)
		(duplicate_pad_numbers_are_jumpers no)
		(fp_line
			(start 0.7874 0.4064)
			(end -0.7874 0.4064)
			(stroke
				(width 0.1524)
				(type default)
			)
			(layer "F.SilkS")
		)
		(fp_line
			(start 0.7874 -0.4064)
			(end 0.7874 0.4064)
			(stroke
				(width 0.1524)
				(type default)
			)
			(layer "F.SilkS")
		)
		(fp_line
			(start -0.7874 0.4064)
			(end -0.7874 -0.4064)
			(stroke
				(width 0.1524)
				(type default)
			)
			(layer "F.SilkS")
		)
		(fp_line
			(start -0.7874 -0.4064)
			(end 0.7874 -0.4064)
			(stroke
				(width 0.1524)
				(type default)
			)
			(layer "F.SilkS")
		)
		(fp_line
			(start 0.67945 0.3048)
			(end 0.120396 0.3048)
			(stroke
				(width 0.1)
				(type default)
			)
			(layer "F.Fab")
		)
		(fp_line
			(start 0.67945 -0.3048)
			(end 0.67945 0.3048)
			(stroke
				(width 0.1)
				(type default)
			)
			(layer "F.Fab")
		)
		(fp_line
			(start 0.12065 -0.2794)
			(end 0.12065 -0.3048)
			(stroke
				(width 0.1)
				(type default)
			)
			(layer "F.Fab")
		)
		(fp_line
			(start 0.12065 -0.3048)
			(end 0.67945 -0.3048)
			(stroke
				(width 0.1)
				(type default)
			)
			(layer "F.Fab")
		)
		(fp_line
			(start 0.120396 0.3048)
			(end 0.120396 0.2794)
			(stroke
				(width 0.1)
				(type default)
			)
			(layer "F.Fab")
		)
		(fp_line
			(start 0.120396 0.2794)
			(end -0.12065 0.2794)
			(stroke
				(width 0.1)
				(type default)
			)
			(layer "F.Fab")
		)
		(fp_line
			(start -0.12065 0.3048)
			(end -0.67945 0.3048)
			(stroke
				(width 0.1)
				(type default)
			)
			(layer "F.Fab")
		)
		(fp_line
			(start -0.12065 0.2794)
			(end -0.12065 0.3048)
			(stroke
				(width 0.1)
				(type default)
			)
			(layer "F.Fab")
		)
		(fp_line
			(start -0.12065 -0.2794)
			(end 0.12065 -0.2794)
			(stroke
				(width 0.1)
				(type default)
			)
			(layer "F.Fab")
		)
		(fp_line
			(start -0.12065 -0.305054)
			(end -0.12065 -0.2794)
			(stroke
				(width 0.1)
				(type default)
			)
			(layer "F.Fab")
		)
		(fp_line
			(start -0.67945 0.3048)
			(end -0.67945 -0.305054)
			(stroke
				(width 0.1)
				(type default)
			)
			(layer "F.Fab")
		)
		(fp_line
			(start -0.67945 -0.305054)
			(end -0.12065 -0.305054)
			(stroke
				(width 0.1)
				(type default)
			)
			(layer "F.Fab")
		)
		(pad "1" smd circle
			(at -0.40005 0 180)
			(size 0 0)
			(layers "F.Cu" "F.Mask" "F.Paste")
			(net "P12V_AUX")
		)
		(pad "2" smd circle
			(at 0.40005 0 180)
			(size 0 0)
			(layers "F.Cu" "F.Mask" "F.Paste")
			(net "GND")
		)
	)
	(footprint ""
		(layer "F.Cu")
		(at 224.20961 -46.524926)
		(property "Reference" "R1673"
			(at 0 0 0)
			(layer "F.SilkS")
			(hide yes)
			(effects
				(font
					(size 1.27 1.27)
				)
			)
		)
		(property "Value" ""
			(at 0 0 0)
			(layer "F.Fab")
			(effects
				(font
					(size 1.27 1.27)
				)
			)
		)
		(duplicate_pad_numbers_are_jumpers no)
		(fp_line
			(start -0.7874 -0.4064)
			(end 0.7874 -0.4064)
			(stroke
				(width 0.1524)
				(type default)
			)
			(layer "F.SilkS")
		)
		(fp_line
			(start -0.7874 0.4064)
			(end -0.7874 -0.4064)
			(stroke
				(width 0.1524)
				(type default)
			)
			(layer "F.SilkS")
		)
		(fp_line
			(start 0.7874 -0.4064)
			(end 0.7874 0.4064)
			(stroke
				(width 0.1524)
				(type default)
			)
			(layer "F.SilkS")
		)
		(fp_line
			(start 0.7874 0.4064)
			(end -0.7874 0.4064)
			(stroke
				(width 0.1524)
				(type default)
			)
			(layer "F.SilkS")
		)
		(fp_line
			(start -0.67945 -0.305054)
			(end -0.12065 -0.305054)
			(stroke
				(width 0.1)
				(type default)
			)
			(layer "F.Fab")
		)
		(fp_line
			(start -0.67945 0.3048)
			(end -0.67945 -0.305054)
			(stroke
				(width 0.1)
				(type default)
			)
			(layer "F.Fab")
		)
		(fp_line
			(start -0.12065 -0.305054)
			(end -0.12065 -0.2794)
			(stroke
				(width 0.1)
				(type default)
			)
			(layer "F.Fab")
		)
		(fp_line
			(start -0.12065 -0.2794)
			(end 0.12065 -0.2794)
			(stroke
				(width 0.1)
				(type default)
			)
			(layer "F.Fab")
		)
		(fp_line
			(start -0.12065 0.2794)
			(end -0.12065 0.3048)
			(stroke
				(width 0.1)
				(type default)
			)
			(layer "F.Fab")
		)
		(fp_line
			(start -0.12065 0.3048)
			(end -0.67945 0.3048)
			(stroke
				(width 0.1)
				(type default)
			)
			(layer "F.Fab")
		)
		(fp_line
			(start 0.120396 0.2794)
			(end -0.12065 0.2794)
			(stroke
				(width 0.1)
				(type default)
			)
			(layer "F.Fab")
		)
		(fp_line
			(start 0.120396 0.3048)
			(end 0.120396 0.2794)
			(stroke
				(width 0.1)
				(type default)
			)
			(layer "F.Fab")
		)
		(fp_line
			(start 0.12065 -0.3048)
			(end 0.67945 -0.3048)
			(stroke
				(width 0.1)
				(type default)
			)
			(layer "F.Fab")
		)
		(fp_line
			(start 0.12065 -0.2794)
			(end 0.12065 -0.3048)
			(stroke
				(width 0.1)
				(type default)
			)
			(layer "F.Fab")
		)
		(fp_line
			(start 0.67945 -0.3048)
			(end 0.67945 0.3048)
			(stroke
				(width 0.1)
				(type default)
			)
			(layer "F.Fab")
		)
		(fp_line
			(start 0.67945 0.3048)
			(end 0.120396 0.3048)
			(stroke
				(width 0.1)
				(type default)
			)
			(layer "F.Fab")
		)
		(pad "1" smd circle
			(at -0.40005 0)
			(size 0 0)
			(layers "F.Cu" "F.Mask" "F.Paste")
			(net "P3V3_E1S_0")
		)
		(pad "2" smd circle
			(at 0.40005 0)
			(size 0 0)
			(layers "F.Cu" "F.Mask" "F.Paste")
			(net "RST_SMB_E1S_0_N")
		)
	)
	(footprint ""
		(layer "F.Cu")
		(at 260.171184 -393.91336 -90)
		(property "Reference" "PR2534"
			(at -4.64312 3.085084 90)
			(unlocked yes)
			(layer "F.SilkS")
			(effects
				(font
					(size 0.7874 0.5842)
					(thickness 0.1524)
				)
				(justify left)
			)
		)
		(property "Value" ""
			(at 0 0 270)
			(layer "F.Fab")
			(effects
				(font
					(size 1.27 1.27)
				)
			)
		)
		(duplicate_pad_numbers_are_jumpers no)
		(fp_line
			(start -3.9878 3.5814)
			(end -3.9878 -3.5814)
			(stroke
				(width 0.1524)
				(type default)
			)
			(layer "F.SilkS")
		)
		(fp_line
			(start 3.9878 3.5814)
			(end -3.9878 3.5814)
			(stroke
				(width 0.1524)
				(type default)
			)
			(layer "F.SilkS")
		)
		(fp_line
			(start -3.9878 -3.5814)
			(end 3.9878 -3.5814)
			(stroke
				(width 0.1524)
				(type default)
			)
			(layer "F.SilkS")
		)
		(fp_line
			(start 3.9878 -3.5814)
			(end 3.9878 3.5814)
			(stroke
				(width 0.1524)
				(type default)
			)
			(layer "F.SilkS")
		)
		(fp_line
			(start -3.5306 3.353054)
			(end -3.5306 -3.353054)
			(stroke
				(width 0.1)
				(type default)
			)
			(layer "F.Fab")
		)
		(fp_line
			(start 3.5306 3.353054)
			(end -3.5306 3.353054)
			(stroke
				(width 0.1)
				(type default)
			)
			(layer "F.Fab")
		)
		(fp_line
			(start -3.5306 -3.353054)
			(end 3.5306 -3.353054)
			(stroke
				(width 0.1)
				(type default)
			)
			(layer "F.Fab")
		)
		(fp_line
			(start 3.5306 -3.353054)
			(end 3.5306 3.353054)
			(stroke
				(width 0.1)
				(type default)
			)
			(layer "F.Fab")
		)
		(pad "1A" smd rect
			(at -2.249932 0 90)
			(size 3.2004 6.858)
			(layers "F.Cu" "F.Mask" "F.Paste")
			(net "P12V_PSU")
		)
		(pad "1B" smd rect
			(at -0.776732 0 270)
			(size 0.254 0.508)
			(layers "F.Cu" "F.Mask" "F.Paste")
			(net "P12V_HSC_SENSE2_R4_P")
		)
		(pad "2A" smd rect
			(at 2.249932 0 90)
			(size 3.2004 6.858)
			(layers "F.Cu" "F.Mask" "F.Paste")
			(net "P12V_MAIN_R")
		)
		(pad "2B" smd rect
			(at 0.776732 0 270)
			(size 0.254 0.508)
			(layers "F.Cu" "F.Mask" "F.Paste")
			(net "P12V_HSC_SENSE2_R4_N")
		)
	)
	(footprint ""
		(layer "F.Cu")
		(at 77.460094 -340.204552)
		(property "Reference" "PR254"
			(at 0 0 0)
			(layer "F.SilkS")
			(hide yes)
			(effects
				(font
					(size 1.27 1.27)
				)
			)
		)
		(property "Value" ""
			(at 0 0 0)
			(layer "F.Fab")
			(effects
				(font
					(size 1.27 1.27)
				)
			)
		)
		(duplicate_pad_numbers_are_jumpers no)
		(fp_line
			(start -0.7874 -0.4064)
			(end 0.7874 -0.4064)
			(stroke
				(width 0.1524)
				(type default)
			)
			(layer "F.SilkS")
		)
		(fp_line
			(start -0.7874 0.4064)
			(end -0.7874 -0.4064)
			(stroke
				(width 0.1524)
				(type default)
			)
			(layer "F.SilkS")
		)
		(fp_line
			(start 0.7874 -0.4064)
			(end 0.7874 0.4064)
			(stroke
				(width 0.1524)
				(type default)
			)
			(layer "F.SilkS")
		)
		(fp_line
			(start 0.7874 0.4064)
			(end -0.7874 0.4064)
			(stroke
				(width 0.1524)
				(type default)
			)
			(layer "F.SilkS")
		)
		(fp_line
			(start -0.67945 -0.305054)
			(end -0.12065 -0.305054)
			(stroke
				(width 0.1)
				(type default)
			)
			(layer "F.Fab")
		)
		(fp_line
			(start -0.67945 0.3048)
			(end -0.67945 -0.305054)
			(stroke
				(width 0.1)
				(type default)
			)
			(layer "F.Fab")
		)
		(fp_line
			(start -0.12065 -0.305054)
			(end -0.12065 -0.2794)
			(stroke
				(width 0.1)
				(type default)
			)
			(layer "F.Fab")
		)
		(fp_line
			(start -0.12065 -0.2794)
			(end 0.12065 -0.2794)
			(stroke
				(width 0.1)
				(type default)
			)
			(layer "F.Fab")
		)
		(fp_line
			(start -0.12065 0.2794)
			(end -0.12065 0.3048)
			(stroke
				(width 0.1)
				(type default)
			)
			(layer "F.Fab")
		)
		(fp_line
			(start -0.12065 0.3048)
			(end -0.67945 0.3048)
			(stroke
				(width 0.1)
				(type default)
			)
			(layer "F.Fab")
		)
		(fp_line
			(start 0.120396 0.2794)
			(end -0.12065 0.2794)
			(stroke
				(width 0.1)
				(type default)
			)
			(layer "F.Fab")
		)
		(fp_line
			(start 0.120396 0.3048)
			(end 0.120396 0.2794)
			(stroke
				(width 0.1)
				(type default)
			)
			(layer "F.Fab")
		)
		(fp_line
			(start 0.12065 -0.3048)
			(end 0.67945 -0.3048)
			(stroke
				(width 0.1)
				(type default)
			)
			(layer "F.Fab")
		)
		(fp_line
			(start 0.12065 -0.2794)
			(end 0.12065 -0.3048)
			(stroke
				(width 0.1)
				(type default)
			)
			(layer "F.Fab")
		)
		(fp_line
			(start 0.67945 -0.3048)
			(end 0.67945 0.3048)
			(stroke
				(width 0.1)
				(type default)
			)
			(layer "F.Fab")
		)
		(fp_line
			(start 0.67945 0.3048)
			(end 0.120396 0.3048)
			(stroke
				(width 0.1)
				(type default)
			)
			(layer "F.Fab")
		)
		(pad "1" smd circle
			(at -0.40005 0)
			(size 0 0)
			(layers "F.Cu" "F.Mask" "F.Paste")
			(net "PVDDCR_CPU1_P1_LSET2")
		)
		(pad "2" smd circle
			(at 0.40005 0)
			(size 0 0)
			(layers "F.Cu" "F.Mask" "F.Paste")
			(net "GND")
		)
	)
	(footprint ""
		(layer "F.Cu")
		(at 176.657 -100.294948 90)
		(property "Reference" "R237"
			(at 0 0 90)
			(layer "F.SilkS")
			(hide yes)
			(effects
				(font
					(size 1.27 1.27)
				)
			)
		)
		(property "Value" ""
			(at 0 0 90)
			(layer "F.Fab")
			(effects
				(font
					(size 1.27 1.27)
				)
			)
		)
		(duplicate_pad_numbers_are_jumpers no)
		(fp_line
			(start 0.7874 -0.4064)
			(end 0.7874 0.4064)
			(stroke
				(width 0.1524)
				(type default)
			)
			(layer "F.SilkS")
		)
		(fp_line
			(start -0.7874 -0.4064)
			(end 0.7874 -0.4064)
			(stroke
				(width 0.1524)
				(type default)
			)
			(layer "F.SilkS")
		)
		(fp_line
			(start 0.7874 0.4064)
			(end -0.7874 0.4064)
			(stroke
				(width 0.1524)
				(type default)
			)
			(layer "F.SilkS")
		)
		(fp_line
			(start -0.7874 0.4064)
			(end -0.7874 -0.4064)
			(stroke
				(width 0.1524)
				(type default)
			)
			(layer "F.SilkS")
		)
		(fp_line
			(start -0.12065 -0.305054)
			(end -0.12065 -0.2794)
			(stroke
				(width 0.1)
				(type default)
			)
			(layer "F.Fab")
		)
		(fp_line
			(start -0.67945 -0.305054)
			(end -0.12065 -0.305054)
			(stroke
				(width 0.1)
				(type default)
			)
			(layer "F.Fab")
		)
		(fp_line
			(start 0.67945 -0.3048)
			(end 0.67945 0.3048)
			(stroke
				(width 0.1)
				(type default)
			)
			(layer "F.Fab")
		)
		(fp_line
			(start 0.12065 -0.3048)
			(end 0.67945 -0.3048)
			(stroke
				(width 0.1)
				(type default)
			)
			(layer "F.Fab")
		)
		(fp_line
			(start 0.12065 -0.2794)
			(end 0.12065 -0.3048)
			(stroke
				(width 0.1)
				(type default)
			)
			(layer "F.Fab")
		)
		(fp_line
			(start -0.12065 -0.2794)
			(end 0.12065 -0.2794)
			(stroke
				(width 0.1)
				(type default)
			)
			(layer "F.Fab")
		)
		(fp_line
			(start 0.120396 0.2794)
			(end -0.12065 0.2794)
			(stroke
				(width 0.1)
				(type default)
			)
			(layer "F.Fab")
		)
		(fp_line
			(start -0.12065 0.2794)
			(end -0.12065 0.3048)
			(stroke
				(width 0.1)
				(type default)
			)
			(layer "F.Fab")
		)
		(fp_line
			(start 0.67945 0.3048)
			(end 0.120396 0.3048)
			(stroke
				(width 0.1)
				(type default)
			)
			(layer "F.Fab")
		)
		(fp_line
			(start 0.120396 0.3048)
			(end 0.120396 0.2794)
			(stroke
				(width 0.1)
				(type default)
			)
			(layer "F.Fab")
		)
		(fp_line
			(start -0.12065 0.3048)
			(end -0.67945 0.3048)
			(stroke
				(width 0.1)
				(type default)
			)
			(layer "F.Fab")
		)
		(fp_line
			(start -0.67945 0.3048)
			(end -0.67945 -0.305054)
			(stroke
				(width 0.1)
				(type default)
			)
			(layer "F.Fab")
		)
		(pad "1" smd circle
			(at -0.40005 0 90)
			(size 0 0)
			(layers "F.Cu" "F.Mask" "F.Paste")
			(net "CPU0_XTRIG_L5")
		)
		(pad "2" smd circle
			(at 0.40005 0 90)
			(size 0 0)
			(layers "F.Cu" "F.Mask" "F.Paste")
			(net "FM_CPU0_XTRIG_L5")
		)
	)
	(footprint ""
		(layer "F.Cu")
		(at 150.500842 -53.083714)
		(property "Reference" "R4090"
			(at 0 0 0)
			(layer "F.SilkS")
			(hide yes)
			(effects
				(font
					(size 1.27 1.27)
				)
			)
		)
		(property "Value" ""
			(at 0 0 0)
			(layer "F.Fab")
			(effects
				(font
					(size 1.27 1.27)
				)
			)
		)
		(duplicate_pad_numbers_are_jumpers no)
		(fp_line
			(start -0.7874 -0.4064)
			(end 0.7874 -0.4064)
			(stroke
				(width 0.1524)
				(type default)
			)
			(layer "F.SilkS")
		)
		(fp_line
			(start -0.7874 0.4064)
			(end -0.7874 -0.4064)
			(stroke
				(width 0.1524)
				(type default)
			)
			(layer "F.SilkS")
		)
		(fp_line
			(start 0.7874 -0.4064)
			(end 0.7874 0.4064)
			(stroke
				(width 0.1524)
				(type default)
			)
			(layer "F.SilkS")
		)
		(fp_line
			(start 0.7874 0.4064)
			(end -0.7874 0.4064)
			(stroke
				(width 0.1524)
				(type default)
			)
			(layer "F.SilkS")
		)
		(fp_line
			(start -0.67945 -0.305054)
			(end -0.12065 -0.305054)
			(stroke
				(width 0.1)
				(type default)
			)
			(layer "F.Fab")
		)
		(fp_line
			(start -0.67945 0.3048)
			(end -0.67945 -0.305054)
			(stroke
				(width 0.1)
				(type default)
			)
			(layer "F.Fab")
		)
		(fp_line
			(start -0.12065 -0.305054)
			(end -0.12065 -0.2794)
			(stroke
				(width 0.1)
				(type default)
			)
			(layer "F.Fab")
		)
		(fp_line
			(start -0.12065 -0.2794)
			(end 0.12065 -0.2794)
			(stroke
				(width 0.1)
				(type default)
			)
			(layer "F.Fab")
		)
		(fp_line
			(start -0.12065 0.2794)
			(end -0.12065 0.3048)
			(stroke
				(width 0.1)
				(type default)
			)
			(layer "F.Fab")
		)
		(fp_line
			(start -0.12065 0.3048)
			(end -0.67945 0.3048)
			(stroke
				(width 0.1)
				(type default)
			)
			(layer "F.Fab")
		)
		(fp_line
			(start 0.120396 0.2794)
			(end -0.12065 0.2794)
			(stroke
				(width 0.1)
				(type default)
			)
			(layer "F.Fab")
		)
		(fp_line
			(start 0.120396 0.3048)
			(end 0.120396 0.2794)
			(stroke
				(width 0.1)
				(type default)
			)
			(layer "F.Fab")
		)
		(fp_line
			(start 0.12065 -0.3048)
			(end 0.67945 -0.3048)
			(stroke
				(width 0.1)
				(type default)
			)
			(layer "F.Fab")
		)
		(fp_line
			(start 0.12065 -0.2794)
			(end 0.12065 -0.3048)
			(stroke
				(width 0.1)
				(type default)
			)
			(layer "F.Fab")
		)
		(fp_line
			(start 0.67945 -0.3048)
			(end 0.67945 0.3048)
			(stroke
				(width 0.1)
				(type default)
			)
			(layer "F.Fab")
		)
		(fp_line
			(start 0.67945 0.3048)
			(end 0.120396 0.3048)
			(stroke
				(width 0.1)
				(type default)
			)
			(layer "F.Fab")
		)
		(pad "1" smd circle
			(at -0.40005 0)
			(size 0 0)
			(layers "F.Cu" "F.Mask" "F.Paste")
			(net "P3V3_AUX")
		)
		(pad "2" smd circle
			(at 0.40005 0)
			(size 0 0)
			(layers "F.Cu" "F.Mask" "F.Paste")
			(net "M2_0_P3V3_ADC_ALERT_R")
		)
	)
)
